(kicad_pcb
	(version 20260206)
	(generator "pcbnew")
	(generator_version "10.0")
	(general
		(thickness 1.6)
		(legacy_teardrops no)
	)
	(paper "A4")
	(title_block
		(title "01162023_DA0F0TEBIF0_F0T_Expander_BD_F_brd_V02_OCP.brd")
		(comment 1 "Grand Teton / footprints 6117-6122 of 9728")
	)
	(layers
		(0 "F.Cu" signal "TOP")
		(4 "In1.Cu" signal "GND")
		(6 "In2.Cu" signal "VCC")
		(8 "In3.Cu" signal "VCC1")
		(10 "In4.Cu" signal "GND1")
		(12 "In5.Cu" signal "IN1")
		(14 "In6.Cu" signal "GND2")
		(16 "In7.Cu" signal "IN2")
		(18 "In8.Cu" signal "GND3")
		(20 "In9.Cu" signal "IN3")
		(22 "In10.Cu" signal "GND4")
		(24 "In11.Cu" signal "IN4")
		(26 "In12.Cu" signal "GND5")
		(28 "In13.Cu" signal "IN5")
		(30 "In14.Cu" signal "GND6")
		(32 "In15.Cu" signal "IN6")
		(34 "In16.Cu" signal "GND7")
		(2 "B.Cu" signal "BOTTOM")
		(9 "F.Adhes" user "F.Adhesive")
		(11 "B.Adhes" user "B.Adhesive")
		(13 "F.Paste" user "Package Geometry/Pastemask Top")
		(15 "B.Paste" user "Package Geometry/Pastemask Bottom")
		(5 "F.SilkS" user "Ref Des/Silkscreen Top")
		(7 "B.SilkS" user "Ref Des/Silkscreen Bottom")
		(1 "F.Mask" user "Board Geometry/Soldermask Top")
		(3 "B.Mask" user "Board Geometry/Soldermask Bottom")
		(17 "Dwgs.User" user "User.Drawings")
		(19 "Cmts.User" user "User.Comments")
		(21 "Eco1.User" user "User.Eco1")
		(23 "Eco2.User" user "User.Eco2")
		(25 "Edge.Cuts" user "Board Geometry/Outline")
		(27 "Margin" user)
		(31 "F.CrtYd" user "Package Geometry/Place Bound Top")
		(29 "B.CrtYd" user "Package Geometry/Place Bound Bottom")
		(35 "F.Fab" user "Ref Des/Assembly Top")
		(33 "B.Fab" user "Ref Des/Assembly Bottom")
	)
	(footprint ""
		(layer "F.Cu")
		(at 38.599872 -154.327352 180)
		(property "Reference" "R26"
			(at 0 0 180)
			(layer "F.SilkS")
			(hide yes)
			(effects
				(font
					(size 1.27 1.27)
				)
			)
		)
		(property "Value" ""
			(at 0 0 180)
			(layer "F.Fab")
			(effects
				(font
					(size 1.27 1.27)
				)
			)
		)
		(duplicate_pad_numbers_are_jumpers no)
		(fp_line
			(start 0.7874 0.4064)
			(end -0.7874 0.4064)
			(stroke
				(width 0.1524)
				(type default)
			)
			(layer "F.SilkS")
		)
		(fp_line
			(start 0.7874 -0.4064)
			(end 0.7874 0.4064)
			(stroke
				(width 0.1524)
				(type default)
			)
			(layer "F.SilkS")
		)
		(fp_line
			(start -0.7874 0.4064)
			(end -0.7874 -0.4064)
			(stroke
				(width 0.1524)
				(type default)
			)
			(layer "F.SilkS")
		)
		(fp_line
			(start -0.7874 -0.4064)
			(end 0.7874 -0.4064)
			(stroke
				(width 0.1524)
				(type default)
			)
			(layer "F.SilkS")
		)
		(fp_line
			(start 0.67945 0.3048)
			(end 0.120396 0.3048)
			(stroke
				(width 0.1)
				(type default)
			)
			(layer "F.Fab")
		)
		(fp_line
			(start 0.67945 -0.3048)
			(end 0.67945 0.3048)
			(stroke
				(width 0.1)
				(type default)
			)
			(layer "F.Fab")
		)
		(fp_line
			(start 0.12065 -0.2794)
			(end 0.12065 -0.3048)
			(stroke
				(width 0.1)
				(type default)
			)
			(layer "F.Fab")
		)
		(fp_line
			(start 0.12065 -0.3048)
			(end 0.67945 -0.3048)
			(stroke
				(width 0.1)
				(type default)
			)
			(layer "F.Fab")
		)
		(fp_line
			(start 0.120396 0.3048)
			(end 0.120396 0.2794)
			(stroke
				(width 0.1)
				(type default)
			)
			(layer "F.Fab")
		)
		(fp_line
			(start 0.120396 0.2794)
			(end -0.12065 0.2794)
			(stroke
				(width 0.1)
				(type default)
			)
			(layer "F.Fab")
		)
		(fp_line
			(start -0.12065 0.3048)
			(end -0.67945 0.3048)
			(stroke
				(width 0.1)
				(type default)
			)
			(layer "F.Fab")
		)
		(fp_line
			(start -0.12065 0.2794)
			(end -0.12065 0.3048)
			(stroke
				(width 0.1)
				(type default)
			)
			(layer "F.Fab")
		)
		(fp_line
			(start -0.12065 -0.2794)
			(end 0.12065 -0.2794)
			(stroke
				(width 0.1)
				(type default)
			)
			(layer "F.Fab")
		)
		(fp_line
			(start -0.12065 -0.305054)
			(end -0.12065 -0.2794)
			(stroke
				(width 0.1)
				(type default)
			)
			(layer "F.Fab")
		)
		(fp_line
			(start -0.67945 0.3048)
			(end -0.67945 -0.305054)
			(stroke
				(width 0.1)
				(type default)
			)
			(layer "F.Fab")
		)
		(fp_line
			(start -0.67945 -0.305054)
			(end -0.12065 -0.305054)
			(stroke
				(width 0.1)
				(type default)
			)
			(layer "F.Fab")
		)
		(pad "1" smd circle
			(at -0.40005 0 180)
			(size 0 0)
			(layers "F.Cu" "F.Mask" "F.Paste")
			(net "NIC0_SLOT_ID0")
		)
		(pad "2" smd circle
			(at 0.40005 0 180)
			(size 0 0)
			(layers "F.Cu" "F.Mask" "F.Paste")
			(net "GND")
		)
	)
	(footprint ""
		(layer "F.Cu")
		(at 52.584096 -29.222954 -90)
		(property "Reference" "PC678"
			(at 0 0 270)
			(layer "F.SilkS")
			(hide yes)
			(effects
				(font
					(size 1.27 1.27)
				)
			)
		)
		(property "Value" ""
			(at 0 0 270)
			(layer "F.Fab")
			(effects
				(font
					(size 1.27 1.27)
				)
			)
		)
		(duplicate_pad_numbers_are_jumpers no)
		(fp_line
			(start -0.7874 0.4064)
			(end -0.7874 -0.4064)
			(stroke
				(width 0.1524)
				(type default)
			)
			(layer "F.SilkS")
		)
		(fp_line
			(start 0.7874 0.4064)
			(end -0.7874 0.4064)
			(stroke
				(width 0.1524)
				(type default)
			)
			(layer "F.SilkS")
		)
		(fp_line
			(start -0.7874 -0.4064)
			(end 0.7874 -0.4064)
			(stroke
				(width 0.1524)
				(type default)
			)
			(layer "F.SilkS")
		)
		(fp_line
			(start 0.7874 -0.4064)
			(end 0.7874 0.4064)
			(stroke
				(width 0.1524)
				(type default)
			)
			(layer "F.SilkS")
		)
		(fp_line
			(start -0.67945 0.3048)
			(end -0.67945 -0.305054)
			(stroke
				(width 0.1)
				(type default)
			)
			(layer "F.Fab")
		)
		(fp_line
			(start -0.12065 0.3048)
			(end -0.67945 0.3048)
			(stroke
				(width 0.1)
				(type default)
			)
			(layer "F.Fab")
		)
		(fp_line
			(start 0.120396 0.3048)
			(end 0.120396 0.2794)
			(stroke
				(width 0.1)
				(type default)
			)
			(layer "F.Fab")
		)
		(fp_line
			(start 0.67945 0.3048)
			(end 0.120396 0.3048)
			(stroke
				(width 0.1)
				(type default)
			)
			(layer "F.Fab")
		)
		(fp_line
			(start -0.12065 0.2794)
			(end -0.12065 0.3048)
			(stroke
				(width 0.1)
				(type default)
			)
			(layer "F.Fab")
		)
		(fp_line
			(start 0.120396 0.2794)
			(end -0.12065 0.2794)
			(stroke
				(width 0.1)
				(type default)
			)
			(layer "F.Fab")
		)
		(fp_line
			(start -0.12065 -0.2794)
			(end 0.12065 -0.2794)
			(stroke
				(width 0.1)
				(type default)
			)
			(layer "F.Fab")
		)
		(fp_line
			(start 0.12065 -0.2794)
			(end 0.12065 -0.3048)
			(stroke
				(width 0.1)
				(type default)
			)
			(layer "F.Fab")
		)
		(fp_line
			(start 0.12065 -0.3048)
			(end 0.67945 -0.3048)
			(stroke
				(width 0.1)
				(type default)
			)
			(layer "F.Fab")
		)
		(fp_line
			(start 0.67945 -0.3048)
			(end 0.67945 0.3048)
			(stroke
				(width 0.1)
				(type default)
			)
			(layer "F.Fab")
		)
		(fp_line
			(start -0.67945 -0.305054)
			(end -0.12065 -0.305054)
			(stroke
				(width 0.1)
				(type default)
			)
			(layer "F.Fab")
		)
		(fp_line
			(start -0.12065 -0.305054)
			(end -0.12065 -0.2794)
			(stroke
				(width 0.1)
				(type default)
			)
			(layer "F.Fab")
		)
		(pad "1" smd circle
			(at -0.40005 0 270)
			(size 0 0)
			(layers "F.Cu" "F.Mask" "F.Paste")
			(net "P3V3_AUX")
		)
		(pad "2" smd circle
			(at 0.40005 0 270)
			(size 0 0)
			(layers "F.Cu" "F.Mask" "F.Paste")
			(net "GND")
		)
	)
	(footprint ""
		(layer "F.Cu")
		(at 13.279374 -281.9654)
		(property "Reference" "PC218"
			(at 0 0 0)
			(layer "F.SilkS")
			(hide yes)
			(effects
				(font
					(size 1.27 1.27)
				)
			)
		)
		(property "Value" ""
			(at 0 0 0)
			(layer "F.Fab")
			(effects
				(font
					(size 1.27 1.27)
				)
			)
		)
		(duplicate_pad_numbers_are_jumpers no)
		(fp_line
			(start -2.750058 -1.988058)
			(end -2.750058 -0.9398)
			(stroke
				(width 0.1524)
				(type default)
			)
			(layer "F.SilkS")
		)
		(fp_line
			(start -2.750058 0.9398)
			(end -2.750058 1.988058)
			(stroke
				(width 0.1524)
				(type default)
			)
			(layer "F.SilkS")
		)
		(fp_line
			(start -2.750058 1.988058)
			(end -1.988058 2.750058)
			(stroke
				(width 0.1524)
				(type default)
			)
			(layer "F.SilkS")
		)
		(fp_line
			(start -1.988058 -2.750058)
			(end -2.750058 -1.988058)
			(stroke
				(width 0.1524)
				(type default)
			)
			(layer "F.SilkS")
		)
		(fp_line
			(start -1.988058 2.750058)
			(end 2.750058 2.750058)
			(stroke
				(width 0.1524)
				(type default)
			)
			(layer "F.SilkS")
		)
		(fp_line
			(start 2.750058 -2.750058)
			(end -1.988058 -2.750058)
			(stroke
				(width 0.1524)
				(type default)
			)
			(layer "F.SilkS")
		)
		(fp_line
			(start 2.750058 -0.9398)
			(end 2.750058 -2.750058)
			(stroke
				(width 0.1524)
				(type default)
			)
			(layer "F.SilkS")
		)
		(fp_line
			(start 2.750058 2.750058)
			(end 2.750058 0.9398)
			(stroke
				(width 0.1524)
				(type default)
			)
			(layer "F.SilkS")
		)
		(fp_line
			(start -2.750058 -2.750058)
			(end -2.750058 2.750058)
			(stroke
				(width 0.1)
				(type default)
			)
			(layer "F.Fab")
		)
		(fp_line
			(start -2.750058 2.750058)
			(end 2.750058 2.750058)
			(stroke
				(width 0.1)
				(type default)
			)
			(layer "F.Fab")
		)
		(fp_line
			(start 2.750058 -2.750058)
			(end -2.750058 -2.750058)
			(stroke
				(width 0.1)
				(type default)
			)
			(layer "F.Fab")
		)
		(fp_line
			(start 2.750058 2.750058)
			(end 2.750058 -2.750058)
			(stroke
				(width 0.1)
				(type default)
			)
			(layer "F.Fab")
		)
		(pad "1" smd rect
			(at -2.199894 0 90)
			(size 1.6002 3.0226)
			(layers "F.Cu" "F.Mask" "F.Paste")
			(net "P1V25_PEX0_R")
		)
		(pad "2" smd rect
			(at 2.199894 0 90)
			(size 1.6002 3.0226)
			(layers "F.Cu" "F.Mask" "F.Paste")
			(net "GND")
		)
	)
	(footprint ""
		(layer "F.Cu")
		(at 203.040234 -141.404848 -90)
		(property "Reference" "R196"
			(at 0 0 270)
			(layer "F.SilkS")
			(hide yes)
			(effects
				(font
					(size 1.27 1.27)
				)
			)
		)
		(property "Value" ""
			(at 0 0 270)
			(layer "F.Fab")
			(effects
				(font
					(size 1.27 1.27)
				)
			)
		)
		(duplicate_pad_numbers_are_jumpers no)
		(fp_line
			(start -0.7874 0.4064)
			(end -0.7874 -0.4064)
			(stroke
				(width 0.1524)
				(type default)
			)
			(layer "F.SilkS")
		)
		(fp_line
			(start 0.7874 0.4064)
			(end -0.7874 0.4064)
			(stroke
				(width 0.1524)
				(type default)
			)
			(layer "F.SilkS")
		)
		(fp_line
			(start -0.7874 -0.4064)
			(end 0.7874 -0.4064)
			(stroke
				(width 0.1524)
				(type default)
			)
			(layer "F.SilkS")
		)
		(fp_line
			(start 0.7874 -0.4064)
			(end 0.7874 0.4064)
			(stroke
				(width 0.1524)
				(type default)
			)
			(layer "F.SilkS")
		)
		(fp_line
			(start -0.67945 0.3048)
			(end -0.67945 -0.305054)
			(stroke
				(width 0.1)
				(type default)
			)
			(layer "F.Fab")
		)
		(fp_line
			(start -0.12065 0.3048)
			(end -0.67945 0.3048)
			(stroke
				(width 0.1)
				(type default)
			)
			(layer "F.Fab")
		)
		(fp_line
			(start 0.120396 0.3048)
			(end 0.120396 0.2794)
			(stroke
				(width 0.1)
				(type default)
			)
			(layer "F.Fab")
		)
		(fp_line
			(start 0.67945 0.3048)
			(end 0.120396 0.3048)
			(stroke
				(width 0.1)
				(type default)
			)
			(layer "F.Fab")
		)
		(fp_line
			(start -0.12065 0.2794)
			(end -0.12065 0.3048)
			(stroke
				(width 0.1)
				(type default)
			)
			(layer "F.Fab")
		)
		(fp_line
			(start 0.120396 0.2794)
			(end -0.12065 0.2794)
			(stroke
				(width 0.1)
				(type default)
			)
			(layer "F.Fab")
		)
		(fp_line
			(start -0.12065 -0.2794)
			(end 0.12065 -0.2794)
			(stroke
				(width 0.1)
				(type default)
			)
			(layer "F.Fab")
		)
		(fp_line
			(start 0.12065 -0.2794)
			(end 0.12065 -0.3048)
			(stroke
				(width 0.1)
				(type default)
			)
			(layer "F.Fab")
		)
		(fp_line
			(start 0.12065 -0.3048)
			(end 0.67945 -0.3048)
			(stroke
				(width 0.1)
				(type default)
			)
			(layer "F.Fab")
		)
		(fp_line
			(start 0.67945 -0.3048)
			(end 0.67945 0.3048)
			(stroke
				(width 0.1)
				(type default)
			)
			(layer "F.Fab")
		)
		(fp_line
			(start -0.67945 -0.305054)
			(end -0.12065 -0.305054)
			(stroke
				(width 0.1)
				(type default)
			)
			(layer "F.Fab")
		)
		(fp_line
			(start -0.12065 -0.305054)
			(end -0.12065 -0.2794)
			(stroke
				(width 0.1)
				(type default)
			)
			(layer "F.Fab")
		)
		(pad "1" smd circle
			(at -0.40005 0 270)
			(size 0 0)
			(layers "F.Cu" "F.Mask" "F.Paste")
			(net "PRSNT_NIC3_R_N")
		)
		(pad "2" smd circle
			(at 0.40005 0 270)
			(size 0 0)
			(layers "F.Cu" "F.Mask" "F.Paste")
			(net "PRSNT_NIC3_N")
		)
	)
	(footprint ""
		(layer "F.Cu")
		(at 363.474 -207.899 180)
		(property "Reference" "R4612"
			(at 0 0 180)
			(layer "F.SilkS")
			(hide yes)
			(effects
				(font
					(size 1.27 1.27)
				)
			)
		)
		(property "Value" ""
			(at 0 0 180)
			(layer "F.Fab")
			(effects
				(font
					(size 1.27 1.27)
				)
			)
		)
		(duplicate_pad_numbers_are_jumpers no)
		(fp_line
			(start 0.7874 0.4064)
			(end -0.7874 0.4064)
			(stroke
				(width 0.1524)
				(type default)
			)
			(layer "F.SilkS")
		)
		(fp_line
			(start 0.7874 -0.4064)
			(end 0.7874 0.4064)
			(stroke
				(width 0.1524)
				(type default)
			)
			(layer "F.SilkS")
		)
		(fp_line
			(start -0.7874 0.4064)
			(end -0.7874 -0.4064)
			(stroke
				(width 0.1524)
				(type default)
			)
			(layer "F.SilkS")
		)
		(fp_line
			(start -0.7874 -0.4064)
			(end 0.7874 -0.4064)
			(stroke
				(width 0.1524)
				(type default)
			)
			(layer "F.SilkS")
		)
		(fp_line
			(start 0.67945 0.3048)
			(end 0.120396 0.3048)
			(stroke
				(width 0.1)
				(type default)
			)
			(layer "F.Fab")
		)
		(fp_line
			(start 0.67945 -0.3048)
			(end 0.67945 0.3048)
			(stroke
				(width 0.1)
				(type default)
			)
			(layer "F.Fab")
		)
		(fp_line
			(start 0.12065 -0.2794)
			(end 0.12065 -0.3048)
			(stroke
				(width 0.1)
				(type default)
			)
			(layer "F.Fab")
		)
		(fp_line
			(start 0.12065 -0.3048)
			(end 0.67945 -0.3048)
			(stroke
				(width 0.1)
				(type default)
			)
			(layer "F.Fab")
		)
		(fp_line
			(start 0.120396 0.3048)
			(end 0.120396 0.2794)
			(stroke
				(width 0.1)
				(type default)
			)
			(layer "F.Fab")
		)
		(fp_line
			(start 0.120396 0.2794)
			(end -0.12065 0.2794)
			(stroke
				(width 0.1)
				(type default)
			)
			(layer "F.Fab")
		)
		(fp_line
			(start -0.12065 0.3048)
			(end -0.67945 0.3048)
			(stroke
				(width 0.1)
				(type default)
			)
			(layer "F.Fab")
		)
		(fp_line
			(start -0.12065 0.2794)
			(end -0.12065 0.3048)
			(stroke
				(width 0.1)
				(type default)
			)
			(layer "F.Fab")
		)
		(fp_line
			(start -0.12065 -0.2794)
			(end 0.12065 -0.2794)
			(stroke
				(width 0.1)
				(type default)
			)
			(layer "F.Fab")
		)
		(fp_line
			(start -0.12065 -0.305054)
			(end -0.12065 -0.2794)
			(stroke
				(width 0.1)
				(type default)
			)
			(layer "F.Fab")
		)
		(fp_line
			(start -0.67945 0.3048)
			(end -0.67945 -0.305054)
			(stroke
				(width 0.1)
				(type default)
			)
			(layer "F.Fab")
		)
		(fp_line
			(start -0.67945 -0.305054)
			(end -0.12065 -0.305054)
			(stroke
				(width 0.1)
				(type default)
			)
			(layer "F.Fab")
		)
		(pad "1" smd circle
			(at -0.40005 0 180)
			(size 0 0)
			(layers "F.Cu" "F.Mask" "F.Paste")
			(net "SSD1_PEX_PWR_EN_R")
		)
		(pad "2" smd circle
			(at 0.40005 0 180)
			(size 0 0)
			(layers "F.Cu" "F.Mask" "F.Paste")
			(net "GND")
		)
	)
	(footprint ""
		(layer "F.Cu")
		(at 365.922814 -22.867366 90)
		(property "Reference" "C3959"
			(at 0 0 90)
			(layer "F.SilkS")
			(hide yes)
			(effects
				(font
					(size 1.27 1.27)
				)
			)
		)
		(property "Value" ""
			(at 0 0 90)
			(layer "F.Fab")
			(effects
				(font
					(size 1.27 1.27)
				)
			)
		)
		(duplicate_pad_numbers_are_jumpers no)
		(fp_line
			(start 0.7874 -0.4064)
			(end 0.7874 0.4064)
			(stroke
				(width 0.1524)
				(type default)
			)
			(layer "F.SilkS")
		)
		(fp_line
			(start -0.7874 -0.4064)
			(end 0.7874 -0.4064)
			(stroke
				(width 0.1524)
				(type default)
			)
			(layer "F.SilkS")
		)
		(fp_line
			(start 0.7874 0.4064)
			(end -0.7874 0.4064)
			(stroke
				(width 0.1524)
				(type default)
			)
			(layer "F.SilkS")
		)
		(fp_line
			(start -0.7874 0.4064)
			(end -0.7874 -0.4064)
			(stroke
				(width 0.1524)
				(type default)
			)
			(layer "F.SilkS")
		)
		(fp_line
			(start -0.12065 -0.305054)
			(end -0.12065 -0.2794)
			(stroke
				(width 0.1)
				(type default)
			)
			(layer "F.Fab")
		)
		(fp_line
			(start -0.67945 -0.305054)
			(end -0.12065 -0.305054)
			(stroke
				(width 0.1)
				(type default)
			)
			(layer "F.Fab")
		)
		(fp_line
			(start 0.67945 -0.3048)
			(end 0.67945 0.3048)
			(stroke
				(width 0.1)
				(type default)
			)
			(layer "F.Fab")
		)
		(fp_line
			(start 0.12065 -0.3048)
			(end 0.67945 -0.3048)
			(stroke
				(width 0.1)
				(type default)
			)
			(layer "F.Fab")
		)
		(fp_line
			(start 0.12065 -0.2794)
			(end 0.12065 -0.3048)
			(stroke
				(width 0.1)
				(type default)
			)
			(layer "F.Fab")
		)
		(fp_line
			(start -0.12065 -0.2794)
			(end 0.12065 -0.2794)
			(stroke
				(width 0.1)
				(type default)
			)
			(layer "F.Fab")
		)
		(fp_line
			(start 0.120396 0.2794)
			(end -0.12065 0.2794)
			(stroke
				(width 0.1)
				(type default)
			)
			(layer "F.Fab")
		)
		(fp_line
			(start -0.12065 0.2794)
			(end -0.12065 0.3048)
			(stroke
				(width 0.1)
				(type default)
			)
			(layer "F.Fab")
		)
		(fp_line
			(start 0.67945 0.3048)
			(end 0.120396 0.3048)
			(stroke
				(width 0.1)
				(type default)
			)
			(layer "F.Fab")
		)
		(fp_line
			(start 0.120396 0.3048)
			(end 0.120396 0.2794)
			(stroke
				(width 0.1)
				(type default)
			)
			(layer "F.Fab")
		)
		(fp_line
			(start -0.12065 0.3048)
			(end -0.67945 0.3048)
			(stroke
				(width 0.1)
				(type default)
			)
			(layer "F.Fab")
		)
		(fp_line
			(start -0.67945 0.3048)
			(end -0.67945 -0.305054)
			(stroke
				(width 0.1)
				(type default)
			)
			(layer "F.Fab")
		)
		(pad "1" smd circle
			(at -0.40005 0 90)
			(size 0 0)
			(layers "F.Cu" "F.Mask" "F.Paste")
			(net "P12V_SSD12")
		)
		(pad "2" smd circle
			(at 0.40005 0 90)
			(size 0 0)
			(layers "F.Cu" "F.Mask" "F.Paste")
			(net "GND")
		)
	)
)
